# T6G (Grand Teton) — schematic netlist excerpt (pin names and nets, part order shuffled) for the footprints in the layout excerpt that follows; sources: Cadence DE-HDL packaged netlist, KiCad conversion of 04192023_DAF0TMB3IC0_F0TG_MB_C_brd_V02_OCP.brd

R3943  Q_RES  0 5% CHIP  pkg 0402LF  page 147 : A = E1S_0_P12V_EN ; B = P12V_E1S_EN_0_R2
C7004  Q_CAPP  470UF 2.5V 20% SPCAP  pkg SMLF  page 345 : A = P0V9_CPU1_RT_2D ; B = GND

(kicad_pcb
	(version 20260206)
	(generator "pcbnew")
	(generator_version "10.0")
	(general
		(thickness 1.6)
		(legacy_teardrops no)
	)
	(paper "A4")
	(title_block
		(title "04192023_DAF0TMB3IC0_F0TG_MB_C_brd_V02_OCP.brd")
		(comment 1 "Grand Teton / footprints 4384-4385 of 8354")
	)
	(layers
		(0 "F.Cu" signal "TOP")
		(4 "In1.Cu" signal "GND")
		(6 "In2.Cu" signal "IN1")
		(8 "In3.Cu" signal "GND1")
		(10 "In4.Cu" signal "IN2")
		(12 "In5.Cu" signal "GND2")
		(14 "In6.Cu" signal "IN3")
		(16 "In7.Cu" signal "GND3")
		(18 "In8.Cu" signal "VCC")
		(20 "In9.Cu" signal "VCC1")
		(22 "In10.Cu" signal "GND4")
		(24 "In11.Cu" signal "IN4")
		(26 "In12.Cu" signal "GND5")
		(28 "In13.Cu" signal "IN5")
		(30 "In14.Cu" signal "GND6")
		(32 "In15.Cu" signal "IN6")
		(34 "In16.Cu" signal "GND7")
		(2 "B.Cu" signal "BOTTOM")
		(9 "F.Adhes" user "F.Adhesive")
		(11 "B.Adhes" user "B.Adhesive")
		(13 "F.Paste" user "Package Geometry/Pastemask Top")
		(15 "B.Paste" user "Package Geometry/Pastemask Bottom")
		(5 "F.SilkS" user "Ref Des/Silkscreen Top")
		(7 "B.SilkS" user "Ref Des/Silkscreen Bottom")
		(1 "F.Mask" user "Board Geometry/Soldermask Top")
		(3 "B.Mask" user "Board Geometry/Soldermask Bottom")
		(17 "Dwgs.User" user "User.Drawings")
		(19 "Cmts.User" user "User.Comments")
		(21 "Eco1.User" user "User.Eco1")
		(23 "Eco2.User" user "User.Eco2")
		(25 "Edge.Cuts" user "Board Geometry/Outline")
		(27 "Margin" user)
		(31 "F.CrtYd" user "Package Geometry/Place Bound Top")
		(29 "B.CrtYd" user "Package Geometry/Place Bound Bottom")
		(35 "F.Fab" user "Ref Des/Assembly Top")
		(33 "B.Fab" user "Ref Des/Assembly Bottom")
	)
	(footprint ""
		(layer "F.Cu")
		(at 67.39001 -400.76882 180)
		(property "Reference" "C7004"
			(at -5.550662 -2.19583 90)
			(unlocked yes)
			(layer "F.SilkS")
			(effects
				(font
					(size 0.7874 0.5842)
					(thickness 0.1524)
				)
				(justify left)
			)
		)
		(property "Value" ""
			(at 0 0 180)
			(layer "F.Fab")
			(effects
				(font
					(size 1.27 1.27)
				)
			)
		)
		(duplicate_pad_numbers_are_jumpers no)
		(fp_line
			(start 4.53898 2.15011)
			(end -4.53898 2.15011)
			(stroke
				(width 0.1524)
				(type default)
			)
			(layer "F.SilkS")
		)
		(fp_line
			(start 4.53898 -2.15011)
			(end 4.53898 2.15011)
			(stroke
				(width 0.1524)
				(type default)
			)
			(layer "F.SilkS")
		)
		(fp_line
			(start -4.53898 2.15011)
			(end -4.53898 -2.15011)
			(stroke
				(width 0.1524)
				(type default)
			)
			(layer "F.SilkS")
		)
		(fp_line
			(start -4.53898 -2.15011)
			(end 4.53898 -2.15011)
			(stroke
				(width 0.1524)
				(type default)
			)
			(layer "F.SilkS")
		)
		(fp_line
			(start -4.53898 -2.150618)
			(end -4.539742 2.152142)
			(stroke
				(width 0.1524)
				(type default)
			)
			(layer "F.SilkS")
		)
		(fp_line
			(start -4.69138 -2.150618)
			(end -4.692396 2.161032)
			(stroke
				(width 0.1524)
				(type default)
			)
			(layer "F.SilkS")
		)
		(fp_line
			(start -4.83108 2.150364)
			(end -4.447794 2.149348)
			(stroke
				(width 0.1524)
				(type default)
			)
			(layer "F.SilkS")
		)
		(fp_line
			(start -4.84378 -2.150618)
			(end -4.53898 -2.150618)
			(stroke
				(width 0.1524)
				(type default)
			)
			(layer "F.SilkS")
		)
		(fp_line
			(start -4.84378 -2.150618)
			(end -4.842256 2.163064)
			(stroke
				(width 0.1524)
				(type default)
			)
			(layer "F.SilkS")
		)
		(fp_line
			(start 3.64998 2.15011)
			(end -3.64998 2.15011)
			(stroke
				(width 0.1)
				(type default)
			)
			(layer "F.Fab")
		)
		(fp_line
			(start 3.64998 -2.15011)
			(end 3.64998 2.15011)
			(stroke
				(width 0.1)
				(type default)
			)
			(layer "F.Fab")
		)
		(fp_line
			(start -3.64998 2.15011)
			(end -3.64998 -2.15011)
			(stroke
				(width 0.1)
				(type default)
			)
			(layer "F.Fab")
		)
		(fp_line
			(start -3.64998 -2.15011)
			(end 3.64998 -2.15011)
			(stroke
				(width 0.1)
				(type default)
			)
			(layer "F.Fab")
		)
		(fp_text user "-"
			(at 2.763774 2.270252 180)
			(unlocked yes)
			(layer "F.SilkS")
			(effects
				(font
					(size 1.905 1.4224)
					(thickness 0.1524)
				)
				(justify left)
			)
		)
		(fp_text user "+"
			(at -4.553712 2.639822 180)
			(unlocked yes)
			(layer "F.SilkS")
			(effects
				(font
					(size 1.905 1.4224)
					(thickness 0.1524)
				)
				(justify left)
			)
		)
		(fp_text user "-"
			(at 4.313174 -0.094488 180)
			(unlocked yes)
			(layer "F.Fab")
			(effects
				(font
					(size 1.905 1.4224)
					(thickness 0.1524)
				)
				(justify left)
			)
		)
		(fp_text user "+"
			(at -6.214872 -0.337058 180)
			(unlocked yes)
			(layer "F.Fab")
			(effects
				(font
					(size 1.905 1.4224)
					(thickness 0.1524)
				)
				(justify left)
			)
		)
		(pad "1" smd rect
			(at -3.199892 0 180)
			(size 2.413 2.8194)
			(layers "F.Cu" "F.Mask" "F.Paste")
			(net "P0V9_CPU1_RT_2D")
		)
		(pad "2" smd rect
			(at 3.199892 0 180)
			(size 2.413 2.8194)
			(layers "F.Cu" "F.Mask" "F.Paste")
			(net "GND")
		)
	)
	(footprint ""
		(layer "F.Cu")
		(at 257.89128 -49.402746 180)
		(property "Reference" "R3943"
			(at 0 0 180)
			(layer "F.SilkS")
			(hide yes)
			(effects
				(font
					(size 1.27 1.27)
				)
			)
		)
		(property "Value" ""
			(at 0 0 180)
			(layer "F.Fab")
			(effects
				(font
					(size 1.27 1.27)
				)
			)
		)
		(duplicate_pad_numbers_are_jumpers no)
		(fp_line
			(start 0.7874 0.4064)
			(end -0.7874 0.4064)
			(stroke
				(width 0.1524)
				(type default)
			)
			(layer "F.SilkS")
		)
		(fp_line
			(start 0.7874 -0.4064)
			(end 0.7874 0.4064)
			(stroke
				(width 0.1524)
				(type default)
			)
			(layer "F.SilkS")
		)
		(fp_line
			(start -0.7874 0.4064)
			(end -0.7874 -0.4064)
			(stroke
				(width 0.1524)
				(type default)
			)
			(layer "F.SilkS")
		)
		(fp_line
			(start -0.7874 -0.4064)
			(end 0.7874 -0.4064)
			(stroke
				(width 0.1524)
				(type default)
			)
			(layer "F.SilkS")
		)
		(fp_line
			(start 0.67945 0.3048)
			(end 0.120396 0.3048)
			(stroke
				(width 0.1)
				(type default)
			)
			(layer "F.Fab")
		)
		(fp_line
			(start 0.67945 -0.3048)
			(end 0.67945 0.3048)
			(stroke
				(width 0.1)
				(type default)
			)
			(layer "F.Fab")
		)
		(fp_line
			(start 0.12065 -0.2794)
			(end 0.12065 -0.3048)
			(stroke
				(width 0.1)
				(type default)
			)
			(layer "F.Fab")
		)
		(fp_line
			(start 0.12065 -0.3048)
			(end 0.67945 -0.3048)
			(stroke
				(width 0.1)
				(type default)
			)
			(layer "F.Fab")
		)
		(fp_line
			(start 0.120396 0.3048)
			(end 0.120396 0.2794)
			(stroke
				(width 0.1)
				(type default)
			)
			(layer "F.Fab")
		)
		(fp_line
			(start 0.120396 0.2794)
			(end -0.12065 0.2794)
			(stroke
				(width 0.1)
				(type default)
			)
			(layer "F.Fab")
		)
		(fp_line
			(start -0.12065 0.3048)
			(end -0.67945 0.3048)
			(stroke
				(width 0.1)
				(type default)
			)
			(layer "F.Fab")
		)
		(fp_line
			(start -0.12065 0.2794)
			(end -0.12065 0.3048)
			(stroke
				(width 0.1)
				(type default)
			)
			(layer "F.Fab")
		)
		(fp_line
			(start -0.12065 -0.2794)
			(end 0.12065 -0.2794)
			(stroke
				(width 0.1)
				(type default)
			)
			(layer "F.Fab")
		)
		(fp_line
			(start -0.12065 -0.305054)
			(end -0.12065 -0.2794)
			(stroke
				(width 0.1)
				(type default)
			)
			(layer "F.Fab")
		)
		(fp_line
			(start -0.67945 0.3048)
			(end -0.67945 -0.305054)
			(stroke
				(width 0.1)
				(type default)
			)
			(layer "F.Fab")
		)
		(fp_line
			(start -0.67945 -0.305054)
			(end -0.12065 -0.305054)
			(stroke
				(width 0.1)
				(type default)
			)
			(layer "F.Fab")
		)
		(pad "1" smd circle
			(at -0.40005 0 180)
			(size 0 0)
			(layers "F.Cu" "F.Mask" "F.Paste")
			(net "E1S_0_P12V_EN")
		)
		(pad "2" smd circle
			(at 0.40005 0 180)
			(size 0 0)
			(layers "F.Cu" "F.Mask" "F.Paste")
			(net "P12V_E1S_EN_0_R2")
		)
	)
)
